# S9S_MB_2U (Grand Teton) — schematic netlist excerpt (pin names and nets, part order shuffled) for the footprints in the layout excerpt that follows; sources: Cadence DE-HDL packaged netlist, KiCad conversion of 03242023_DA0F0TMBIJ0_F0T_Motherboard_J_brd_V01_OCP.brd

R3581  Q_RES  0 5% CHIP  pkg 0402LF  page 231 : A = SMB_INA230_3V3AUX_SDA_R ; B = SMB_INA230_3V3AUX_SDA

U150  74LVC2G17GW  IC  pkg SOT363  page 224
  A0  = FM_PS_EN_PLD_R
  GND  = GND
  A1  = NC_U150_A1
  B1  = NC_U150_B1
  VCC  = P3V3_AUX
  B0  = FM_PS_EN_PLD_BUF1

(kicad_pcb
	(version 20260206)
	(generator "pcbnew")
	(generator_version "10.0")
	(general
		(thickness 1.6)
		(legacy_teardrops no)
	)
	(paper "A4")
	(title_block
		(title "03242023_DA0F0TMBIJ0_F0T_Motherboard_J_brd_V01_OCP.brd")
		(comment 1 "Grand Teton / footprints 1214-1215 of 6105")
	)
	(layers
		(0 "F.Cu" signal "TOP")
		(4 "In1.Cu" signal "GND")
		(6 "In2.Cu" signal "IN1")
		(8 "In3.Cu" signal "GND1")
		(10 "In4.Cu" signal "IN2")
		(12 "In5.Cu" signal "GND2")
		(14 "In6.Cu" signal "IN3")
		(16 "In7.Cu" signal "GND3")
		(18 "In8.Cu" signal "VCC")
		(20 "In9.Cu" signal "VCC1")
		(22 "In10.Cu" signal "GND4")
		(24 "In11.Cu" signal "IN4")
		(26 "In12.Cu" signal "GND5")
		(28 "In13.Cu" signal "IN5")
		(30 "In14.Cu" signal "GND6")
		(32 "In15.Cu" signal "IN6")
		(34 "In16.Cu" signal "GND7")
		(2 "B.Cu" signal "BOTTOM")
		(9 "F.Adhes" user "F.Adhesive")
		(11 "B.Adhes" user "B.Adhesive")
		(13 "F.Paste" user "Package Geometry/Pastemask Top")
		(15 "B.Paste" user "Package Geometry/Pastemask Bottom")
		(5 "F.SilkS" user "Ref Des/Silkscreen Top")
		(7 "B.SilkS" user "Ref Des/Silkscreen Bottom")
		(1 "F.Mask" user "Board Geometry/Soldermask Top")
		(3 "B.Mask" user "Board Geometry/Soldermask Bottom")
		(17 "Dwgs.User" user "User.Drawings")
		(19 "Cmts.User" user "User.Comments")
		(21 "Eco1.User" user "User.Eco1")
		(23 "Eco2.User" user "User.Eco2")
		(25 "Edge.Cuts" user "Board Geometry/Outline")
		(27 "Margin" user)
		(31 "F.CrtYd" user "Package Geometry/Place Bound Top")
		(29 "B.CrtYd" user "Package Geometry/Place Bound Bottom")
		(35 "F.Fab" user "Ref Des/Assembly Top")
		(33 "B.Fab" user "Ref Des/Assembly Bottom")
	)
	(footprint ""
		(layer "F.Cu")
		(at 128.401572 -133.050026)
		(property "Reference" "R3581"
			(at 0 0 0)
			(layer "F.SilkS")
			(hide yes)
			(effects
				(font
					(size 1.27 1.27)
				)
			)
		)
		(property "Value" ""
			(at 0 0 0)
			(layer "F.Fab")
			(effects
				(font
					(size 1.27 1.27)
				)
			)
		)
		(duplicate_pad_numbers_are_jumpers no)
		(fp_line
			(start -0.7874 -0.4064)
			(end 0.7874 -0.4064)
			(stroke
				(width 0.1524)
				(type default)
			)
			(layer "F.SilkS")
		)
		(fp_line
			(start -0.7874 0.4064)
			(end -0.7874 -0.4064)
			(stroke
				(width 0.1524)
				(type default)
			)
			(layer "F.SilkS")
		)
		(fp_line
			(start 0.7874 -0.4064)
			(end 0.7874 0.4064)
			(stroke
				(width 0.1524)
				(type default)
			)
			(layer "F.SilkS")
		)
		(fp_line
			(start 0.7874 0.4064)
			(end -0.7874 0.4064)
			(stroke
				(width 0.1524)
				(type default)
			)
			(layer "F.SilkS")
		)
		(fp_line
			(start -0.67945 -0.305054)
			(end -0.12065 -0.305054)
			(stroke
				(width 0.1)
				(type default)
			)
			(layer "F.Fab")
		)
		(fp_line
			(start -0.67945 0.3048)
			(end -0.67945 -0.305054)
			(stroke
				(width 0.1)
				(type default)
			)
			(layer "F.Fab")
		)
		(fp_line
			(start -0.12065 -0.305054)
			(end -0.12065 -0.2794)
			(stroke
				(width 0.1)
				(type default)
			)
			(layer "F.Fab")
		)
		(fp_line
			(start -0.12065 -0.2794)
			(end 0.12065 -0.2794)
			(stroke
				(width 0.1)
				(type default)
			)
			(layer "F.Fab")
		)
		(fp_line
			(start -0.12065 0.2794)
			(end -0.12065 0.3048)
			(stroke
				(width 0.1)
				(type default)
			)
			(layer "F.Fab")
		)
		(fp_line
			(start -0.12065 0.3048)
			(end -0.67945 0.3048)
			(stroke
				(width 0.1)
				(type default)
			)
			(layer "F.Fab")
		)
		(fp_line
			(start 0.120396 0.2794)
			(end -0.12065 0.2794)
			(stroke
				(width 0.1)
				(type default)
			)
			(layer "F.Fab")
		)
		(fp_line
			(start 0.120396 0.3048)
			(end 0.120396 0.2794)
			(stroke
				(width 0.1)
				(type default)
			)
			(layer "F.Fab")
		)
		(fp_line
			(start 0.12065 -0.3048)
			(end 0.67945 -0.3048)
			(stroke
				(width 0.1)
				(type default)
			)
			(layer "F.Fab")
		)
		(fp_line
			(start 0.12065 -0.2794)
			(end 0.12065 -0.3048)
			(stroke
				(width 0.1)
				(type default)
			)
			(layer "F.Fab")
		)
		(fp_line
			(start 0.67945 -0.3048)
			(end 0.67945 0.3048)
			(stroke
				(width 0.1)
				(type default)
			)
			(layer "F.Fab")
		)
		(fp_line
			(start 0.67945 0.3048)
			(end 0.120396 0.3048)
			(stroke
				(width 0.1)
				(type default)
			)
			(layer "F.Fab")
		)
		(pad "1" smd circle
			(at -0.40005 0)
			(size 0 0)
			(layers "F.Cu" "F.Mask" "F.Paste")
			(net "SMB_INA230_3V3AUX_SDA_R")
		)
		(pad "2" smd circle
			(at 0.40005 0)
			(size 0 0)
			(layers "F.Cu" "F.Mask" "F.Paste")
			(net "SMB_INA230_3V3AUX_SDA")
		)
	)
	(footprint ""
		(layer "F.Cu")
		(at 140.843 -78.500478)
		(property "Reference" "U150"
			(at -1.16078 -1.98628 0)
			(unlocked yes)
			(layer "F.SilkS")
			(effects
				(font
					(size 0.7874 0.5842)
					(thickness 0.1524)
				)
				(justify left)
			)
		)
		(property "Value" ""
			(at 0 0 0)
			(layer "F.Fab")
			(effects
				(font
					(size 1.27 1.27)
				)
			)
		)
		(duplicate_pad_numbers_are_jumpers no)
		(fp_line
			(start -1.3462 -1.100074)
			(end -0.670052 -1.100074)
			(stroke
				(width 0.1524)
				(type default)
			)
			(layer "F.SilkS")
		)
		(fp_line
			(start -1.3462 1.100074)
			(end -1.3462 -1.100074)
			(stroke
				(width 0.1524)
				(type default)
			)
			(layer "F.SilkS")
		)
		(fp_line
			(start -0.670052 -1.100074)
			(end 0 -0.381)
			(stroke
				(width 0.1524)
				(type default)
			)
			(layer "F.SilkS")
		)
		(fp_line
			(start 0 -0.381)
			(end 0.670052 -1.100074)
			(stroke
				(width 0.1524)
				(type default)
			)
			(layer "F.SilkS")
		)
		(fp_line
			(start 0.670052 -1.100074)
			(end 1.3462 -1.100074)
			(stroke
				(width 0.1524)
				(type default)
			)
			(layer "F.SilkS")
		)
		(fp_line
			(start 1.3462 -1.100074)
			(end 1.3462 1.100074)
			(stroke
				(width 0.1524)
				(type default)
			)
			(layer "F.SilkS")
		)
		(fp_line
			(start 1.3462 1.100074)
			(end -1.3462 1.100074)
			(stroke
				(width 0.1524)
				(type default)
			)
			(layer "F.SilkS")
		)
		(fp_poly
			(pts
				(xy -1.524 -0.649986) (xy -2.286 -0.268986) (xy -2.286 -1.030986)
			)
			(stroke
				(width 0)
				(type default)
			)
			(fill yes)
			(layer "F.SilkS")
		)
		(fp_line
			(start -1.100074 -0.8001)
			(end -0.670052 -0.8001)
			(stroke
				(width 0.1)
				(type default)
			)
			(layer "F.Fab")
		)
		(fp_line
			(start -1.100074 0.8001)
			(end -1.100074 -0.8001)
			(stroke
				(width 0.1)
				(type default)
			)
			(layer "F.Fab")
		)
		(fp_line
			(start -0.670052 -1.100074)
			(end 0.670052 -1.100074)
			(stroke
				(width 0.1)
				(type default)
			)
			(layer "F.Fab")
		)
		(fp_line
			(start -0.670052 -0.8001)
			(end -0.670052 -1.100074)
			(stroke
				(width 0.1)
				(type default)
			)
			(layer "F.Fab")
		)
		(fp_line
			(start -0.670052 0.8001)
			(end -1.100074 0.8001)
			(stroke
				(width 0.1)
				(type default)
			)
			(layer "F.Fab")
		)
		(fp_line
			(start -0.670052 0.8001)
			(end -0.670052 -0.8001)
			(stroke
				(width 0.1)
				(type default)
			)
			(layer "F.Fab")
		)
		(fp_line
			(start -0.670052 1.100074)
			(end -0.670052 0.8001)
			(stroke
				(width 0.1)
				(type default)
			)
			(layer "F.Fab")
		)
		(fp_line
			(start 0.670052 -1.100074)
			(end 0.670052 -0.8001)
			(stroke
				(width 0.1)
				(type default)
			)
			(layer "F.Fab")
		)
		(fp_line
			(start 0.670052 -0.8001)
			(end 0.670052 0.8001)
			(stroke
				(width 0.1)
				(type default)
			)
			(layer "F.Fab")
		)
		(fp_line
			(start 0.670052 -0.8001)
			(end 1.100074 -0.8001)
			(stroke
				(width 0.1)
				(type default)
			)
			(layer "F.Fab")
		)
		(fp_line
			(start 0.670052 0.8001)
			(end 0.670052 1.100074)
			(stroke
				(width 0.1)
				(type default)
			)
			(layer "F.Fab")
		)
		(fp_line
			(start 0.670052 1.100074)
			(end -0.670052 1.100074)
			(stroke
				(width 0.1)
				(type default)
			)
			(layer "F.Fab")
		)
		(fp_line
			(start 1.100074 -0.8001)
			(end 1.100074 0.8001)
			(stroke
				(width 0.1)
				(type default)
			)
			(layer "F.Fab")
		)
		(fp_line
			(start 1.100074 0.8001)
			(end 0.670052 0.8001)
			(stroke
				(width 0.1)
				(type default)
			)
			(layer "F.Fab")
		)
		(fp_poly
			(pts
				(xy -1.524 -0.649986) (xy -2.286 -1.030986) (xy -2.286 -0.268986)
			)
			(stroke
				(width 0)
				(type default)
			)
			(fill yes)
			(layer "F.Fab")
		)
		(pad "1" smd rect
			(at -0.94996 -0.649986 270)
			(size 0.4064 0.508)
			(layers "F.Cu" "F.Mask" "F.Paste")
			(net "FM_PS_EN_PLD_R")
		)
		(pad "2" smd rect
			(at -0.94996 0 270)
			(size 0.4064 0.508)
			(layers "F.Cu" "F.Mask" "F.Paste")
			(net "GND")
		)
		(pad "3" smd rect
			(at -0.94996 0.649986 270)
			(size 0.4064 0.508)
			(layers "F.Cu" "F.Mask" "F.Paste")
			(net "NC_U150_A1")
		)
		(pad "4" smd rect
			(at 0.94996 0.649986 270)
			(size 0.4064 0.508)
			(layers "F.Cu" "F.Mask" "F.Paste")
			(net "NC_U150_B1")
		)
		(pad "5" smd rect
			(at 0.94996 0 270)
			(size 0.4064 0.508)
			(layers "F.Cu" "F.Mask" "F.Paste")
			(net "P3V3_AUX")
		)
		(pad "6" smd rect
			(at 0.94996 -0.649986 270)
			(size 0.4064 0.508)
			(layers "F.Cu" "F.Mask" "F.Paste")
			(net "FM_PS_EN_PLD_BUF1")
		)
	)
)
